# T6G (Grand Teton) — schematic netlist excerpt (pin names and nets, part order shuffled) for the footprints in the layout excerpt that follows; sources: Cadence DE-HDL packaged netlist, KiCad conversion of 04192023_DAF0TMB3IC0_F0TG_MB_C_brd_V02_OCP.brd

C975  Q_CAP  1UF 4V 20% X6S  pkg 0201  page 301 : A = P0V9_CPU0_RT2_2A ; B = GND
PR206  Q_RES  2.2 1% CHIP  pkg 0402LF  page 215 : A = PVDDCR_CPU0_P1_PVCC ; B = PVDDCR_SOC_P1_VCC2
R559  Q_RES  2.2K 5% CHIP  pkg 0402LF  page 55 : A = PVDD18_S5_P1 ; B = RST_CPU1_SYS_N

(kicad_pcb
	(version 20260206)
	(generator "pcbnew")
	(generator_version "10.0")
	(general
		(thickness 1.6)
		(legacy_teardrops no)
	)
	(paper "A4")
	(title_block
		(title "04192023_DAF0TMB3IC0_F0TG_MB_C_brd_V02_OCP.brd")
		(comment 1 "Grand Teton / footprints 6158-6160 of 8354")
	)
	(layers
		(0 "F.Cu" signal "TOP")
		(4 "In1.Cu" signal "GND")
		(6 "In2.Cu" signal "IN1")
		(8 "In3.Cu" signal "GND1")
		(10 "In4.Cu" signal "IN2")
		(12 "In5.Cu" signal "GND2")
		(14 "In6.Cu" signal "IN3")
		(16 "In7.Cu" signal "GND3")
		(18 "In8.Cu" signal "VCC")
		(20 "In9.Cu" signal "VCC1")
		(22 "In10.Cu" signal "GND4")
		(24 "In11.Cu" signal "IN4")
		(26 "In12.Cu" signal "GND5")
		(28 "In13.Cu" signal "IN5")
		(30 "In14.Cu" signal "GND6")
		(32 "In15.Cu" signal "IN6")
		(34 "In16.Cu" signal "GND7")
		(2 "B.Cu" signal "BOTTOM")
		(9 "F.Adhes" user "F.Adhesive")
		(11 "B.Adhes" user "B.Adhesive")
		(13 "F.Paste" user "Package Geometry/Pastemask Top")
		(15 "B.Paste" user "Package Geometry/Pastemask Bottom")
		(5 "F.SilkS" user "Ref Des/Silkscreen Top")
		(7 "B.SilkS" user "Ref Des/Silkscreen Bottom")
		(1 "F.Mask" user "Board Geometry/Soldermask Top")
		(3 "B.Mask" user "Board Geometry/Soldermask Bottom")
		(17 "Dwgs.User" user "User.Drawings")
		(19 "Cmts.User" user "User.Comments")
		(21 "Eco1.User" user "User.Eco1")
		(23 "Eco2.User" user "User.Eco2")
		(25 "Edge.Cuts" user "Board Geometry/Outline")
		(27 "Margin" user)
		(31 "F.CrtYd" user "Package Geometry/Place Bound Top")
		(29 "B.CrtYd" user "Package Geometry/Place Bound Bottom")
		(35 "F.Fab" user "Ref Des/Assembly Top")
		(33 "B.Fab" user "Ref Des/Assembly Bottom")
	)
	(footprint ""
		(layer "B.Cu")
		(at 126.276862 -164.133276 90)
		(property "Reference" "PR206"
			(at 0 0 90)
			(layer "B.SilkS")
			(hide yes)
			(effects
				(font
					(size 1.27 1.27)
				)
				(justify mirror)
			)
		)
		(property "Value" ""
			(at 0 0 90)
			(layer "B.Fab")
			(effects
				(font
					(size 1.27 1.27)
				)
				(justify mirror)
			)
		)
		(duplicate_pad_numbers_are_jumpers no)
		(fp_line
			(start 0.7874 -0.4064)
			(end -0.7874 -0.4064)
			(stroke
				(width 0.1524)
				(type default)
			)
			(layer "B.SilkS")
		)
		(fp_line
			(start -0.7874 -0.4064)
			(end -0.7874 0.4064)
			(stroke
				(width 0.1524)
				(type default)
			)
			(layer "B.SilkS")
		)
		(fp_line
			(start 0.7874 0.4064)
			(end 0.7874 -0.4064)
			(stroke
				(width 0.1524)
				(type default)
			)
			(layer "B.SilkS")
		)
		(fp_line
			(start -0.7874 0.4064)
			(end 0.7874 0.4064)
			(stroke
				(width 0.1524)
				(type default)
			)
			(layer "B.SilkS")
		)
		(fp_line
			(start 0.67945 -0.305054)
			(end 0.12065 -0.305054)
			(stroke
				(width 0.1)
				(type default)
			)
			(layer "B.Fab")
		)
		(fp_line
			(start 0.12065 -0.305054)
			(end 0.12065 -0.2794)
			(stroke
				(width 0.1)
				(type default)
			)
			(layer "B.Fab")
		)
		(fp_line
			(start -0.12065 -0.3048)
			(end -0.67945 -0.3048)
			(stroke
				(width 0.1)
				(type default)
			)
			(layer "B.Fab")
		)
		(fp_line
			(start -0.67945 -0.3048)
			(end -0.67945 0.3048)
			(stroke
				(width 0.1)
				(type default)
			)
			(layer "B.Fab")
		)
		(fp_line
			(start 0.12065 -0.2794)
			(end -0.12065 -0.2794)
			(stroke
				(width 0.1)
				(type default)
			)
			(layer "B.Fab")
		)
		(fp_line
			(start -0.12065 -0.2794)
			(end -0.12065 -0.3048)
			(stroke
				(width 0.1)
				(type default)
			)
			(layer "B.Fab")
		)
		(fp_line
			(start 0.12065 0.2794)
			(end 0.12065 0.3048)
			(stroke
				(width 0.1)
				(type default)
			)
			(layer "B.Fab")
		)
		(fp_line
			(start -0.120396 0.2794)
			(end 0.12065 0.2794)
			(stroke
				(width 0.1)
				(type default)
			)
			(layer "B.Fab")
		)
		(fp_line
			(start 0.67945 0.3048)
			(end 0.67945 -0.305054)
			(stroke
				(width 0.1)
				(type default)
			)
			(layer "B.Fab")
		)
		(fp_line
			(start 0.12065 0.3048)
			(end 0.67945 0.3048)
			(stroke
				(width 0.1)
				(type default)
			)
			(layer "B.Fab")
		)
		(fp_line
			(start -0.120396 0.3048)
			(end -0.120396 0.2794)
			(stroke
				(width 0.1)
				(type default)
			)
			(layer "B.Fab")
		)
		(fp_line
			(start -0.67945 0.3048)
			(end -0.120396 0.3048)
			(stroke
				(width 0.1)
				(type default)
			)
			(layer "B.Fab")
		)
		(pad "1" smd circle
			(at 0.40005 0 270)
			(size 0 0)
			(layers "B.Cu" "B.Mask" "B.Paste")
			(net "PVDDCR_CPU0_P1_PVCC")
		)
		(pad "2" smd circle
			(at -0.40005 0 270)
			(size 0 0)
			(layers "B.Cu" "B.Mask" "B.Paste")
			(net "PVDDCR_SOC_P1_VCC2")
		)
	)
	(footprint ""
		(layer "B.Cu")
		(at 156.154374 -322.805552)
		(property "Reference" "R559"
			(at 0 0 0)
			(layer "B.SilkS")
			(hide yes)
			(effects
				(font
					(size 1.27 1.27)
				)
				(justify mirror)
			)
		)
		(property "Value" ""
			(at 0 0 0)
			(layer "B.Fab")
			(effects
				(font
					(size 1.27 1.27)
				)
				(justify mirror)
			)
		)
		(duplicate_pad_numbers_are_jumpers no)
		(fp_line
			(start -0.7874 -0.4064)
			(end -0.7874 0.4064)
			(stroke
				(width 0.1524)
				(type default)
			)
			(layer "B.SilkS")
		)
		(fp_line
			(start -0.7874 0.4064)
			(end 0.7874 0.4064)
			(stroke
				(width 0.1524)
				(type default)
			)
			(layer "B.SilkS")
		)
		(fp_line
			(start 0.7874 -0.4064)
			(end -0.7874 -0.4064)
			(stroke
				(width 0.1524)
				(type default)
			)
			(layer "B.SilkS")
		)
		(fp_line
			(start 0.7874 0.4064)
			(end 0.7874 -0.4064)
			(stroke
				(width 0.1524)
				(type default)
			)
			(layer "B.SilkS")
		)
		(fp_line
			(start -0.67945 -0.3048)
			(end -0.67945 0.3048)
			(stroke
				(width 0.1)
				(type default)
			)
			(layer "B.Fab")
		)
		(fp_line
			(start -0.67945 0.3048)
			(end -0.120396 0.3048)
			(stroke
				(width 0.1)
				(type default)
			)
			(layer "B.Fab")
		)
		(fp_line
			(start -0.12065 -0.3048)
			(end -0.67945 -0.3048)
			(stroke
				(width 0.1)
				(type default)
			)
			(layer "B.Fab")
		)
		(fp_line
			(start -0.12065 -0.2794)
			(end -0.12065 -0.3048)
			(stroke
				(width 0.1)
				(type default)
			)
			(layer "B.Fab")
		)
		(fp_line
			(start -0.120396 0.2794)
			(end 0.12065 0.2794)
			(stroke
				(width 0.1)
				(type default)
			)
			(layer "B.Fab")
		)
		(fp_line
			(start -0.120396 0.3048)
			(end -0.120396 0.2794)
			(stroke
				(width 0.1)
				(type default)
			)
			(layer "B.Fab")
		)
		(fp_line
			(start 0.12065 -0.305054)
			(end 0.12065 -0.2794)
			(stroke
				(width 0.1)
				(type default)
			)
			(layer "B.Fab")
		)
		(fp_line
			(start 0.12065 -0.2794)
			(end -0.12065 -0.2794)
			(stroke
				(width 0.1)
				(type default)
			)
			(layer "B.Fab")
		)
		(fp_line
			(start 0.12065 0.2794)
			(end 0.12065 0.3048)
			(stroke
				(width 0.1)
				(type default)
			)
			(layer "B.Fab")
		)
		(fp_line
			(start 0.12065 0.3048)
			(end 0.67945 0.3048)
			(stroke
				(width 0.1)
				(type default)
			)
			(layer "B.Fab")
		)
		(fp_line
			(start 0.67945 -0.305054)
			(end 0.12065 -0.305054)
			(stroke
				(width 0.1)
				(type default)
			)
			(layer "B.Fab")
		)
		(fp_line
			(start 0.67945 0.3048)
			(end 0.67945 -0.305054)
			(stroke
				(width 0.1)
				(type default)
			)
			(layer "B.Fab")
		)
		(pad "1" smd circle
			(at 0.40005 0 180)
			(size 0 0)
			(layers "B.Cu" "B.Mask" "B.Paste")
			(net "PVDD18_S5_P1")
		)
		(pad "2" smd circle
			(at -0.40005 0 180)
			(size 0 0)
			(layers "B.Cu" "B.Mask" "B.Paste")
			(net "RST_CPU1_SYS_N")
		)
	)
	(footprint ""
		(layer "B.Cu")
		(at 419.806374 -395.148562 90)
		(property "Reference" "C975"
			(at 0 0 90)
			(layer "B.SilkS")
			(hide yes)
			(effects
				(font
					(size 1.27 1.27)
				)
				(justify mirror)
			)
		)
		(property "Value" ""
			(at 0 0 90)
			(layer "B.Fab")
			(effects
				(font
					(size 1.27 1.27)
				)
				(justify mirror)
			)
		)
		(duplicate_pad_numbers_are_jumpers no)
		(fp_line
			(start 0.299974 -0.150114)
			(end -0.299974 -0.150114)
			(stroke
				(width 0.1)
				(type default)
			)
			(layer "B.Fab")
		)
		(fp_line
			(start -0.299974 -0.150114)
			(end -0.299974 0.150114)
			(stroke
				(width 0.1)
				(type default)
			)
			(layer "B.Fab")
		)
		(fp_line
			(start 0.299974 0.150114)
			(end 0.299974 -0.150114)
			(stroke
				(width 0.1)
				(type default)
			)
			(layer "B.Fab")
		)
		(fp_line
			(start -0.299974 0.150114)
			(end 0.299974 0.150114)
			(stroke
				(width 0.1)
				(type default)
			)
			(layer "B.Fab")
		)
		(pad "1" smd rect
			(at 0.2667 0 270)
			(size 0.3048 0.381)
			(layers "B.Cu" "B.Mask" "B.Paste")
			(net "P0V9_CPU0_RT2_2A")
		)
		(pad "2" smd rect
			(at -0.2667 0 270)
			(size 0.3048 0.381)
			(layers "B.Cu" "B.Mask" "B.Paste")
			(net "GND")
		)
	)
)
